# T6G (Grand Teton) — schematic netlist excerpt (pin names and nets, part order shuffled) for the footprints in the layout excerpt that follows; sources: Cadence DE-HDL packaged netlist, KiCad conversion of 04192023_DAF0TMB3IC0_F0TG_MB_C_brd_V02_OCP.brd

PR3957  Q_RES  49.9 1% CHIP  pkg 0603LF  page 147 : A = P12V_AUX ; B = P12V_E1S_AVIN_PD_0

(kicad_pcb
	(version 20260206)
	(generator "pcbnew")
	(generator_version "10.0")
	(general
		(thickness 1.6)
		(legacy_teardrops no)
	)
	(paper "A4")
	(title_block
		(title "04192023_DAF0TMB3IC0_F0TG_MB_C_brd_V02_OCP.brd")
		(comment 1 "Grand Teton / footprints 2782-2782 of 8354")
	)
	(layers
		(0 "F.Cu" signal "TOP")
		(4 "In1.Cu" signal "GND")
		(6 "In2.Cu" signal "IN1")
		(8 "In3.Cu" signal "GND1")
		(10 "In4.Cu" signal "IN2")
		(12 "In5.Cu" signal "GND2")
		(14 "In6.Cu" signal "IN3")
		(16 "In7.Cu" signal "GND3")
		(18 "In8.Cu" signal "VCC")
		(20 "In9.Cu" signal "VCC1")
		(22 "In10.Cu" signal "GND4")
		(24 "In11.Cu" signal "IN4")
		(26 "In12.Cu" signal "GND5")
		(28 "In13.Cu" signal "IN5")
		(30 "In14.Cu" signal "GND6")
		(32 "In15.Cu" signal "IN6")
		(34 "In16.Cu" signal "GND7")
		(2 "B.Cu" signal "BOTTOM")
		(9 "F.Adhes" user "F.Adhesive")
		(11 "B.Adhes" user "B.Adhesive")
		(13 "F.Paste" user "Package Geometry/Pastemask Top")
		(15 "B.Paste" user "Package Geometry/Pastemask Bottom")
		(5 "F.SilkS" user "Ref Des/Silkscreen Top")
		(7 "B.SilkS" user "Ref Des/Silkscreen Bottom")
		(1 "F.Mask" user "Board Geometry/Soldermask Top")
		(3 "B.Mask" user "Board Geometry/Soldermask Bottom")
		(17 "Dwgs.User" user "User.Drawings")
		(19 "Cmts.User" user "User.Comments")
		(21 "Eco1.User" user "User.Eco1")
		(23 "Eco2.User" user "User.Eco2")
		(25 "Edge.Cuts" user "Board Geometry/Outline")
		(27 "Margin" user)
		(31 "F.CrtYd" user "Package Geometry/Place Bound Top")
		(29 "B.CrtYd" user "Package Geometry/Place Bound Bottom")
		(35 "F.Fab" user "Ref Des/Assembly Top")
		(33 "B.Fab" user "Ref Des/Assembly Bottom")
	)
	(footprint ""
		(layer "F.Cu")
		(at 249.765312 -54.440582 -90)
		(property "Reference" "PR3957"
			(at 0 0 270)
			(layer "F.SilkS")
			(hide yes)
			(effects
				(font
					(size 1.27 1.27)
				)
			)
		)
		(property "Value" ""
			(at 0 0 270)
			(layer "F.Fab")
			(effects
				(font
					(size 1.27 1.27)
				)
			)
		)
		(duplicate_pad_numbers_are_jumpers no)
		(fp_line
			(start -1.2954 0.5842)
			(end -1.2954 -0.5842)
			(stroke
				(width 0.1524)
				(type default)
			)
			(layer "F.SilkS")
		)
		(fp_line
			(start 1.2954 0.5842)
			(end -1.2954 0.5842)
			(stroke
				(width 0.1524)
				(type default)
			)
			(layer "F.SilkS")
		)
		(fp_line
			(start -1.2954 -0.5842)
			(end 1.2954 -0.5842)
			(stroke
				(width 0.1524)
				(type default)
			)
			(layer "F.SilkS")
		)
		(fp_line
			(start 1.2954 -0.5842)
			(end 1.2954 0.5842)
			(stroke
				(width 0.1524)
				(type default)
			)
			(layer "F.SilkS")
		)
		(fp_line
			(start -0.8636 0.4572)
			(end -0.8636 0.4318)
			(stroke
				(width 0.1)
				(type default)
			)
			(layer "F.Fab")
		)
		(fp_line
			(start 0.8636 0.4572)
			(end -0.8636 0.4572)
			(stroke
				(width 0.1)
				(type default)
			)
			(layer "F.Fab")
		)
		(fp_line
			(start -0.8636 0.4318)
			(end -0.8636 0.4064)
			(stroke
				(width 0.1)
				(type default)
			)
			(layer "F.Fab")
		)
		(fp_line
			(start -1.1938 0.4064)
			(end -1.1938 -0.406654)
			(stroke
				(width 0.1)
				(type default)
			)
			(layer "F.Fab")
		)
		(fp_line
			(start -0.8636 0.4064)
			(end -1.1938 0.4064)
			(stroke
				(width 0.1)
				(type default)
			)
			(layer "F.Fab")
		)
		(fp_line
			(start 0.8636 0.4064)
			(end 0.8636 0.4572)
			(stroke
				(width 0.1)
				(type default)
			)
			(layer "F.Fab")
		)
		(fp_line
			(start 1.1938 0.4064)
			(end 0.8636 0.4064)
			(stroke
				(width 0.1)
				(type default)
			)
			(layer "F.Fab")
		)
		(fp_line
			(start -1.1938 -0.406654)
			(end -0.8636 -0.406654)
			(stroke
				(width 0.1)
				(type default)
			)
			(layer "F.Fab")
		)
		(fp_line
			(start -0.8636 -0.406654)
			(end -0.8636 -0.4572)
			(stroke
				(width 0.1)
				(type default)
			)
			(layer "F.Fab")
		)
		(fp_line
			(start 0.8636 -0.406654)
			(end 1.1938 -0.406654)
			(stroke
				(width 0.1)
				(type default)
			)
			(layer "F.Fab")
		)
		(fp_line
			(start 1.1938 -0.406654)
			(end 1.1938 0.4064)
			(stroke
				(width 0.1)
				(type default)
			)
			(layer "F.Fab")
		)
		(fp_line
			(start -0.8636 -0.4572)
			(end 0.8636 -0.4572)
			(stroke
				(width 0.1)
				(type default)
			)
			(layer "F.Fab")
		)
		(fp_line
			(start 0.8636 -0.4572)
			(end 0.8636 -0.406654)
			(stroke
				(width 0.1)
				(type default)
			)
			(layer "F.Fab")
		)
		(pad "1" smd rect
			(at -0.7366 0 180)
			(size 0.7112 0.8128)
			(layers "F.Cu" "F.Mask" "F.Paste")
			(net "P12V_AUX")
		)
		(pad "2" smd rect
			(at 0.7366 0 180)
			(size 0.7112 0.8128)
			(layers "F.Cu" "F.Mask" "F.Paste")
			(net "P12V_E1S_AVIN_PD_0")
		)
	)
)
